(kicad_pcb
	(version 20260206)
	(generator "pcbnew")
	(generator_version "10.0")
	(general
		(thickness 1.6)
		(legacy_teardrops no)
	)
	(paper "A4")
	(title_block
		(title "baseboard — 13948-1b.1110WZS1818.brd")
		(comment 1 "Honey Badger (Wiwynn) / footprints 521-527 of 2523")
	)
	(layers
		(0 "F.Cu" signal "TOP")
		(4 "In1.Cu" signal "L2GND")
		(6 "In2.Cu" signal "L3")
		(8 "In3.Cu" signal "L4VCC")
		(10 "In4.Cu" signal "L5VCC")
		(12 "In5.Cu" signal "L6")
		(14 "In6.Cu" signal "L7GND")
		(2 "B.Cu" signal "BOTTOM")
		(9 "F.Adhes" user "F.Adhesive")
		(11 "B.Adhes" user "B.Adhesive")
		(13 "F.Paste" user "Package Geometry/Pastemask Top")
		(15 "B.Paste" user "Package Geometry/Pastemask Bottom")
		(5 "F.SilkS" user "Ref Des/Silkscreen Top")
		(7 "B.SilkS" user "Ref Des/Silkscreen Bottom")
		(1 "F.Mask" user "Board Geometry/Soldermask Top")
		(3 "B.Mask" user "Board Geometry/Soldermask Bottom")
		(17 "Dwgs.User" user "User.Drawings")
		(19 "Cmts.User" user "User.Comments")
		(21 "Eco1.User" user "User.Eco1")
		(23 "Eco2.User" user "User.Eco2")
		(25 "Edge.Cuts" user "Board Geometry/Outline")
		(27 "Margin" user)
		(31 "F.CrtYd" user "Package Geometry/Place Bound Top")
		(29 "B.CrtYd" user "Package Geometry/Place Bound Bottom")
		(35 "F.Fab" user "Ref Des/Assembly Top")
		(33 "B.Fab" user "Ref Des/Assembly Bottom")
	)
	(footprint ""
		(layer "F.Cu")
		(at 14.682216 -224.08388 -90)
		(property "Reference" "SR298"
			(at 0 0 270)
			(layer "F.SilkS")
			(hide yes)
			(effects
				(font
					(size 1.27 1.27)
				)
			)
		)
		(property "Value" "0R2J-2-GP"
			(at 0.064008 -3.993896 270)
			(unlocked yes)
			(layer "F.Fab")
			(hide yes)
			(effects
				(font
					(size 1.016 1.016)
					(thickness 0.1524)
				)
			)
		)
		(property "Device Type" "R402H16"
			(at 0.064008 -5.517896 270)
			(unlocked yes)
			(layer "F.Fab")
			(hide yes)
			(effects
				(font
					(size 1.016 1.016)
					(thickness 0.1524)
				)
			)
		)
		(duplicate_pad_numbers_are_jumpers no)
		(fp_line
			(start -0.508 -0.9398)
			(end -0.508 0.9398)
			(stroke
				(width 0.1524)
				(type default)
			)
			(layer "F.SilkS")
		)
		(fp_line
			(start 0.508 -0.9398)
			(end -0.508 -0.9398)
			(stroke
				(width 0.1524)
				(type default)
			)
			(layer "F.SilkS")
		)
		(fp_rect
			(start -0.508 0.9398)
			(end 0.508 -0.9398)
			(stroke
				(width 0)
				(type default)
			)
			(fill no)
			(layer "F.CrtYd")
		)
		(fp_rect
			(start -0.508 0.9398)
			(end 0.508 -0.9398)
			(stroke
				(width 0)
				(type default)
			)
			(fill no)
			(layer "F.Fab")
		)
		(pad "1" smd custom
			(at 0 -0.4445 270)
			(size 0.1397 0.1397)
			(layers "F.Cu" "F.Mask" "F.Paste")
			(net "PWR_SDA")
			(options
				(clearance outline)
				(anchor circle)
			)
			(primitives
				(gr_poly
					(pts
						(arc
							(start -0.1778 -0.2794)
							(mid -0.249642 -0.249642)
							(end -0.2794 -0.1778)
						)
						(arc
							(start -0.2794 0.1778)
							(mid -0.249642 0.249642)
							(end -0.1778 0.2794)
						)
						(arc
							(start 0.1778 0.2794)
							(mid 0.249642 0.249642)
							(end 0.2794 0.1778)
						)
						(arc
							(start 0.2794 -0.1778)
							(mid 0.249642 -0.249642)
							(end 0.1778 -0.2794)
						)
					)
					(width 0)
					(fill yes)
				)
			)
		)
		(pad "2" smd custom
			(at 0 0.4445 270)
			(size 0.1397 0.1397)
			(layers "F.Cu" "F.Mask" "F.Paste")
			(net "EXP_SDA_0")
			(options
				(clearance outline)
				(anchor circle)
			)
			(primitives
				(gr_poly
					(pts
						(arc
							(start -0.1778 -0.2794)
							(mid -0.249642 -0.249642)
							(end -0.2794 -0.1778)
						)
						(arc
							(start -0.2794 0.1778)
							(mid -0.249642 0.249642)
							(end -0.1778 0.2794)
						)
						(arc
							(start 0.1778 0.2794)
							(mid 0.249642 0.249642)
							(end 0.2794 0.1778)
						)
						(arc
							(start 0.2794 -0.1778)
							(mid 0.249642 -0.249642)
							(end 0.1778 -0.2794)
						)
					)
					(width 0)
					(fill yes)
				)
			)
		)
	)
	(footprint ""
		(layer "F.Cu")
		(at 48.895 -220.853 90)
		(property "Reference" "R2171"
			(at 0 0 90)
			(layer "F.SilkS")
			(hide yes)
			(effects
				(font
					(size 1.27 1.27)
				)
			)
		)
		(property "Value" "100KR2J-4-GP"
			(at -1.1811 -1.1303 90)
			(unlocked yes)
			(layer "F.Fab")
			(hide yes)
			(effects
				(font
					(size 1.016 1.016)
					(thickness 0.1524)
				)
			)
		)
		(property "Device Type" "R402H15"
			(at -1.1811 -2.6543 90)
			(unlocked yes)
			(layer "F.Fab")
			(hide yes)
			(effects
				(font
					(size 1.016 1.016)
					(thickness 0.1524)
				)
			)
		)
		(duplicate_pad_numbers_are_jumpers no)
		(fp_line
			(start 0.508 -0.9398)
			(end -0.508 -0.9398)
			(stroke
				(width 0.1524)
				(type default)
			)
			(layer "F.SilkS")
		)
		(fp_line
			(start -0.508 -0.9398)
			(end -0.508 0.9398)
			(stroke
				(width 0.1524)
				(type default)
			)
			(layer "F.SilkS")
		)
		(fp_rect
			(start -0.508 0.9398)
			(end 0.508 -0.9398)
			(stroke
				(width 0)
				(type default)
			)
			(fill no)
			(layer "F.CrtYd")
		)
		(fp_rect
			(start -0.508 0.9398)
			(end 0.508 -0.9398)
			(stroke
				(width 0)
				(type default)
			)
			(fill no)
			(layer "F.Fab")
		)
		(pad "1" smd custom
			(at 0 -0.4445 90)
			(size 0.1397 0.1397)
			(layers "F.Cu" "F.Mask" "F.Paste")
			(net "MB0_VCAP_R")
			(options
				(clearance outline)
				(anchor circle)
			)
			(primitives
				(gr_poly
					(pts
						(arc
							(start -0.1778 -0.2794)
							(mid -0.249642 -0.249642)
							(end -0.2794 -0.1778)
						)
						(arc
							(start -0.2794 0.1778)
							(mid -0.249642 0.249642)
							(end -0.1778 0.2794)
						)
						(arc
							(start 0.1778 0.2794)
							(mid 0.249642 0.249642)
							(end 0.2794 0.1778)
						)
						(arc
							(start 0.2794 -0.1778)
							(mid 0.249642 -0.249642)
							(end 0.1778 -0.2794)
						)
					)
					(width 0)
					(fill yes)
				)
			)
		)
		(pad "2" smd custom
			(at 0 0.4445 90)
			(size 0.1397 0.1397)
			(layers "F.Cu" "F.Mask" "F.Paste")
			(net "MB0_PSET_R")
			(options
				(clearance outline)
				(anchor circle)
			)
			(primitives
				(gr_poly
					(pts
						(arc
							(start -0.1778 -0.2794)
							(mid -0.249642 -0.249642)
							(end -0.2794 -0.1778)
						)
						(arc
							(start -0.2794 0.1778)
							(mid -0.249642 0.249642)
							(end -0.1778 0.2794)
						)
						(arc
							(start 0.1778 0.2794)
							(mid 0.249642 0.249642)
							(end 0.2794 0.1778)
						)
						(arc
							(start 0.2794 -0.1778)
							(mid 0.249642 -0.249642)
							(end 0.1778 -0.2794)
						)
					)
					(width 0)
					(fill yes)
				)
			)
		)
	)
	(footprint ""
		(layer "F.Cu")
		(at 95.89897 -82.804 -90)
		(property "Reference" "SR799"
			(at 0 0 270)
			(layer "F.SilkS")
			(hide yes)
			(effects
				(font
					(size 1.27 1.27)
				)
			)
		)
		(property "Value" "4K75R2F-1-GP"
			(at 0.064008 -3.993896 270)
			(unlocked yes)
			(layer "F.Fab")
			(hide yes)
			(effects
				(font
					(size 1.016 1.016)
					(thickness 0.1524)
				)
			)
		)
		(property "Device Type" "R402H16"
			(at 0.064008 -5.517896 270)
			(unlocked yes)
			(layer "F.Fab")
			(hide yes)
			(effects
				(font
					(size 1.016 1.016)
					(thickness 0.1524)
				)
			)
		)
		(duplicate_pad_numbers_are_jumpers no)
		(fp_line
			(start -0.508 -0.9398)
			(end -0.508 0.9398)
			(stroke
				(width 0.1524)
				(type default)
			)
			(layer "F.SilkS")
		)
		(fp_line
			(start 0.508 -0.9398)
			(end -0.508 -0.9398)
			(stroke
				(width 0.1524)
				(type default)
			)
			(layer "F.SilkS")
		)
		(fp_rect
			(start -0.508 0.9398)
			(end 0.508 -0.9398)
			(stroke
				(width 0)
				(type default)
			)
			(fill no)
			(layer "F.CrtYd")
		)
		(fp_rect
			(start -0.508 0.9398)
			(end 0.508 -0.9398)
			(stroke
				(width 0)
				(type default)
			)
			(fill no)
			(layer "F.Fab")
		)
		(pad "1" smd custom
			(at 0 -0.4445 270)
			(size 0.1397 0.1397)
			(layers "F.Cu" "F.Mask" "F.Paste")
			(net "EXP_CLK_SEL1")
			(options
				(clearance outline)
				(anchor circle)
			)
			(primitives
				(gr_poly
					(pts
						(arc
							(start -0.1778 -0.2794)
							(mid -0.249642 -0.249642)
							(end -0.2794 -0.1778)
						)
						(arc
							(start -0.2794 0.1778)
							(mid -0.249642 0.249642)
							(end -0.1778 0.2794)
						)
						(arc
							(start 0.1778 0.2794)
							(mid 0.249642 0.249642)
							(end 0.2794 0.1778)
						)
						(arc
							(start 0.2794 -0.1778)
							(mid 0.249642 -0.249642)
							(end 0.1778 -0.2794)
						)
					)
					(width 0)
					(fill yes)
				)
			)
		)
		(pad "2" smd custom
			(at 0 0.4445 270)
			(size 0.1397 0.1397)
			(layers "F.Cu" "F.Mask" "F.Paste")
			(net "GND")
			(options
				(clearance outline)
				(anchor circle)
			)
			(primitives
				(gr_poly
					(pts
						(arc
							(start -0.1778 -0.2794)
							(mid -0.249642 -0.249642)
							(end -0.2794 -0.1778)
						)
						(arc
							(start -0.2794 0.1778)
							(mid -0.249642 0.249642)
							(end -0.1778 0.2794)
						)
						(arc
							(start 0.1778 0.2794)
							(mid 0.249642 0.249642)
							(end 0.2794 0.1778)
						)
						(arc
							(start 0.2794 -0.1778)
							(mid 0.249642 -0.249642)
							(end 0.1778 -0.2794)
						)
					)
					(width 0)
					(fill yes)
				)
			)
		)
	)
	(footprint ""
		(layer "F.Cu")
		(at 272.923 -44.958 180)
		(property "Reference" "PC44"
			(at 0 0 180)
			(layer "F.SilkS")
			(hide yes)
			(effects
				(font
					(size 1.27 1.27)
				)
			)
		)
		(property "Value" "SC22U25V5MX-GP"
			(at -0.0762 -6.1214 180)
			(unlocked yes)
			(layer "F.Fab")
			(hide yes)
			(effects
				(font
					(size 1.016 1.016)
					(thickness 0.1524)
				)
			)
		)
		(property "Device Type" "C805H58"
			(at -0.0762 -8.1534 180)
			(unlocked yes)
			(layer "F.Fab")
			(hide yes)
			(effects
				(font
					(size 1.016 1.016)
					(thickness 0.1524)
				)
			)
		)
		(duplicate_pad_numbers_are_jumpers no)
		(fp_line
			(start 0.635 0)
			(end -0.635 0)
			(stroke
				(width 0.508)
				(type default)
			)
			(layer "F.SilkS")
		)
		(fp_rect
			(start -0.9652 1.778)
			(end 0.9652 -1.778)
			(stroke
				(width 0)
				(type default)
			)
			(fill no)
			(layer "F.CrtYd")
		)
		(fp_poly
			(pts
				(xy -0.9652 -1.778) (xy 0.9652 -1.778) (xy 0.9652 1.778) (xy -0.9652 1.778)
			)
			(stroke
				(width 0)
				(type default)
			)
			(fill no)
			(layer "F.Fab")
		)
		(pad "1" smd rect
			(at 0 -0.9652 180)
			(size 1.397 1.143)
			(layers "F.Cu" "F.Mask" "F.Paste")
			(net "P1V8_STBY_VIN")
		)
		(pad "2" smd rect
			(at 0 0.9652 180)
			(size 1.397 1.143)
			(layers "F.Cu" "F.Mask" "F.Paste")
			(net "GND")
		)
	)
	(footprint ""
		(layer "F.Cu")
		(at 180.140864 -38.172136 180)
		(property "Reference" "R393"
			(at 0 0 180)
			(layer "F.SilkS")
			(hide yes)
			(effects
				(font
					(size 1.27 1.27)
				)
			)
		)
		(property "Value" "4K75R2F-1-GP"
			(at 0.064008 -3.993896 180)
			(unlocked yes)
			(layer "F.Fab")
			(hide yes)
			(effects
				(font
					(size 1.016 1.016)
					(thickness 0.1524)
				)
			)
		)
		(property "Device Type" "R402H16"
			(at 0.064008 -5.517896 180)
			(unlocked yes)
			(layer "F.Fab")
			(hide yes)
			(effects
				(font
					(size 1.016 1.016)
					(thickness 0.1524)
				)
			)
		)
		(duplicate_pad_numbers_are_jumpers no)
		(fp_line
			(start 0.508 -0.9398)
			(end -0.508 -0.9398)
			(stroke
				(width 0.1524)
				(type default)
			)
			(layer "F.SilkS")
		)
		(fp_line
			(start -0.508 -0.9398)
			(end -0.508 0.9398)
			(stroke
				(width 0.1524)
				(type default)
			)
			(layer "F.SilkS")
		)
		(fp_rect
			(start -0.508 0.9398)
			(end 0.508 -0.9398)
			(stroke
				(width 0)
				(type default)
			)
			(fill no)
			(layer "F.CrtYd")
		)
		(fp_rect
			(start -0.508 0.9398)
			(end 0.508 -0.9398)
			(stroke
				(width 0)
				(type default)
			)
			(fill no)
			(layer "F.Fab")
		)
		(pad "1" smd custom
			(at 0 -0.4445 180)
			(size 0.1397 0.1397)
			(layers "F.Cu" "F.Mask" "F.Paste")
			(net "PHY_AD4")
			(options
				(clearance outline)
				(anchor circle)
			)
			(primitives
				(gr_poly
					(pts
						(arc
							(start -0.1778 -0.2794)
							(mid -0.249642 -0.249642)
							(end -0.2794 -0.1778)
						)
						(arc
							(start -0.2794 0.1778)
							(mid -0.249642 0.249642)
							(end -0.1778 0.2794)
						)
						(arc
							(start 0.1778 0.2794)
							(mid 0.249642 0.249642)
							(end 0.2794 0.1778)
						)
						(arc
							(start 0.2794 -0.1778)
							(mid 0.249642 -0.249642)
							(end 0.1778 -0.2794)
						)
					)
					(width 0)
					(fill yes)
				)
			)
		)
		(pad "2" smd custom
			(at 0 0.4445 180)
			(size 0.1397 0.1397)
			(layers "F.Cu" "F.Mask" "F.Paste")
			(net "GND")
			(options
				(clearance outline)
				(anchor circle)
			)
			(primitives
				(gr_poly
					(pts
						(arc
							(start -0.1778 -0.2794)
							(mid -0.249642 -0.249642)
							(end -0.2794 -0.1778)
						)
						(arc
							(start -0.2794 0.1778)
							(mid -0.249642 0.249642)
							(end -0.1778 0.2794)
						)
						(arc
							(start 0.1778 0.2794)
							(mid 0.249642 0.249642)
							(end 0.2794 0.1778)
						)
						(arc
							(start 0.2794 -0.1778)
							(mid 0.249642 -0.249642)
							(end 0.1778 -0.2794)
						)
					)
					(width 0)
					(fill yes)
				)
			)
		)
	)
	(footprint ""
		(layer "F.Cu")
		(at 96.501966 -63.119)
		(property "Reference" "SR679"
			(at 0 0 0)
			(layer "F.SilkS")
			(hide yes)
			(effects
				(font
					(size 1.27 1.27)
				)
			)
		)
		(property "Value" "4K7R2F-GP"
			(at 0.064008 -3.993896 0)
			(unlocked yes)
			(layer "F.Fab")
			(hide yes)
			(effects
				(font
					(size 1.016 1.016)
					(thickness 0.1524)
				)
			)
		)
		(property "Device Type" "R402H16"
			(at 0.064008 -5.517896 0)
			(unlocked yes)
			(layer "F.Fab")
			(hide yes)
			(effects
				(font
					(size 1.016 1.016)
					(thickness 0.1524)
				)
			)
		)
		(duplicate_pad_numbers_are_jumpers no)
		(fp_line
			(start -0.508 -0.9398)
			(end -0.508 0.9398)
			(stroke
				(width 0.1524)
				(type default)
			)
			(layer "F.SilkS")
		)
		(fp_line
			(start 0.508 -0.9398)
			(end -0.508 -0.9398)
			(stroke
				(width 0.1524)
				(type default)
			)
			(layer "F.SilkS")
		)
		(fp_rect
			(start -0.508 0.9398)
			(end 0.508 -0.9398)
			(stroke
				(width 0)
				(type default)
			)
			(fill no)
			(layer "F.CrtYd")
		)
		(fp_rect
			(start -0.508 0.9398)
			(end 0.508 -0.9398)
			(stroke
				(width 0)
				(type default)
			)
			(fill no)
			(layer "F.Fab")
		)
		(pad "1" smd custom
			(at 0 -0.4445)
			(size 0.1397 0.1397)
			(layers "F.Cu" "F.Mask" "F.Paste")
			(net "P1V8_C")
			(options
				(clearance outline)
				(anchor circle)
			)
			(primitives
				(gr_poly
					(pts
						(arc
							(start -0.1778 -0.2794)
							(mid -0.249642 -0.249642)
							(end -0.2794 -0.1778)
						)
						(arc
							(start -0.2794 0.1778)
							(mid -0.249642 0.249642)
							(end -0.1778 0.2794)
						)
						(arc
							(start 0.1778 0.2794)
							(mid 0.249642 0.249642)
							(end 0.2794 0.1778)
						)
						(arc
							(start 0.2794 -0.1778)
							(mid 0.249642 -0.249642)
							(end 0.1778 -0.2794)
						)
					)
					(width 0)
					(fill yes)
				)
			)
		)
		(pad "2" smd custom
			(at 0 0.4445)
			(size 0.1397 0.1397)
			(layers "F.Cu" "F.Mask" "F.Paste")
			(net "ICE0_TCK")
			(options
				(clearance outline)
				(anchor circle)
			)
			(primitives
				(gr_poly
					(pts
						(arc
							(start -0.1778 -0.2794)
							(mid -0.249642 -0.249642)
							(end -0.2794 -0.1778)
						)
						(arc
							(start -0.2794 0.1778)
							(mid -0.249642 0.249642)
							(end -0.1778 0.2794)
						)
						(arc
							(start 0.1778 0.2794)
							(mid 0.249642 0.249642)
							(end 0.2794 0.1778)
						)
						(arc
							(start 0.2794 -0.1778)
							(mid 0.249642 -0.249642)
							(end 0.1778 -0.2794)
						)
					)
					(width 0)
					(fill yes)
				)
			)
		)
	)
	(footprint ""
		(layer "F.Cu")
		(at 56.896 -211.074)
		(property "Reference" "PR9007"
			(at 0 0 0)
			(layer "F.SilkS")
			(hide yes)
			(effects
				(font
					(size 1.27 1.27)
				)
			)
		)
		(property "Value" "0R2J-2-GP"
			(at 0.064008 -3.993896 0)
			(unlocked yes)
			(layer "F.Fab")
			(hide yes)
			(effects
				(font
					(size 1.016 1.016)
					(thickness 0.1524)
				)
			)
		)
		(property "Device Type" "R402H16"
			(at 0.064008 -5.517896 0)
			(unlocked yes)
			(layer "F.Fab")
			(hide yes)
			(effects
				(font
					(size 1.016 1.016)
					(thickness 0.1524)
				)
			)
		)
		(duplicate_pad_numbers_are_jumpers no)
		(fp_line
			(start -0.508 -0.9398)
			(end -0.508 0.9398)
			(stroke
				(width 0.1524)
				(type default)
			)
			(layer "F.SilkS")
		)
		(fp_line
			(start 0.508 -0.9398)
			(end -0.508 -0.9398)
			(stroke
				(width 0.1524)
				(type default)
			)
			(layer "F.SilkS")
		)
		(fp_rect
			(start -0.508 0.9398)
			(end 0.508 -0.9398)
			(stroke
				(width 0)
				(type default)
			)
			(fill no)
			(layer "F.CrtYd")
		)
		(fp_rect
			(start -0.508 0.9398)
			(end 0.508 -0.9398)
			(stroke
				(width 0)
				(type default)
			)
			(fill no)
			(layer "F.Fab")
		)
		(pad "1" smd custom
			(at 0 -0.4445)
			(size 0.1397 0.1397)
			(layers "F.Cu" "F.Mask" "F.Paste")
			(net "HSW_SDA_2")
			(options
				(clearance outline)
				(anchor circle)
			)
			(primitives
				(gr_poly
					(pts
						(arc
							(start -0.1778 -0.2794)
							(mid -0.249642 -0.249642)
							(end -0.2794 -0.1778)
						)
						(arc
							(start -0.2794 0.1778)
							(mid -0.249642 0.249642)
							(end -0.1778 0.2794)
						)
						(arc
							(start 0.1778 0.2794)
							(mid 0.249642 0.249642)
							(end 0.2794 0.1778)
						)
						(arc
							(start 0.2794 -0.1778)
							(mid 0.249642 -0.249642)
							(end 0.1778 -0.2794)
						)
					)
					(width 0)
					(fill yes)
				)
			)
		)
		(pad "2" smd custom
			(at 0 0.4445)
			(size 0.1397 0.1397)
			(layers "F.Cu" "F.Mask" "F.Paste")
			(net "BMC_I2C_SDA_10")
			(options
				(clearance outline)
				(anchor circle)
			)
			(primitives
				(gr_poly
					(pts
						(arc
							(start -0.1778 -0.2794)
							(mid -0.249642 -0.249642)
							(end -0.2794 -0.1778)
						)
						(arc
							(start -0.2794 0.1778)
							(mid -0.249642 0.249642)
							(end -0.1778 0.2794)
						)
						(arc
							(start 0.1778 0.2794)
							(mid 0.249642 0.249642)
							(end 0.2794 0.1778)
						)
						(arc
							(start 0.2794 -0.1778)
							(mid 0.249642 -0.249642)
							(end 0.1778 -0.2794)
						)
					)
					(width 0)
					(fill yes)
				)
			)
		)
	)
)
